(kicad_pcb
	(version 20260206)
	(generator "pcbnew")
	(generator_version "10.0")
	(general
		(thickness 1.6)
		(legacy_teardrops no)
	)
	(paper "A4")
	(title_block
		(title "v1-chassis-manager — T6M_CM_d_v01_1031_1645.brd")
		(comment 1 "Open CloudServer (Microsoft) / footprints 532-542 of 2512")
	)
	(layers
		(0 "F.Cu" signal "TOP")
		(4 "In1.Cu" signal "GND1")
		(6 "In2.Cu" signal "IN1")
		(8 "In3.Cu" signal "VCC1")
		(10 "In4.Cu" signal "VCC2")
		(12 "In5.Cu" signal "GND2")
		(14 "In6.Cu" signal "IN2")
		(16 "In7.Cu" signal "IN3")
		(18 "In8.Cu" signal "GND3")
		(2 "B.Cu" signal "BOTTOM")
		(9 "F.Adhes" user "F.Adhesive")
		(11 "B.Adhes" user "B.Adhesive")
		(13 "F.Paste" user "Package Geometry/Pastemask Top")
		(15 "B.Paste" user "Package Geometry/Pastemask Bottom")
		(5 "F.SilkS" user "Ref Des/Silkscreen Top")
		(7 "B.SilkS" user "Ref Des/Silkscreen Bottom")
		(1 "F.Mask" user "Board Geometry/Soldermask Top")
		(3 "B.Mask" user "Board Geometry/Soldermask Bottom")
		(17 "Dwgs.User" user "User.Drawings")
		(19 "Cmts.User" user "User.Comments")
		(21 "Eco1.User" user "User.Eco1")
		(23 "Eco2.User" user "User.Eco2")
		(25 "Edge.Cuts" user "Board Geometry/Outline")
		(27 "Margin" user)
		(31 "F.CrtYd" user "Package Geometry/Place Bound Top")
		(29 "B.CrtYd" user "Package Geometry/Place Bound Bottom")
		(35 "F.Fab" user "Ref Des/Assembly Top")
		(33 "B.Fab" user "Ref Des/Assembly Bottom")
	)
	(footprint ""
		(layer "F.Cu")
		(at 148.193252 -138.48715)
		(property "Reference" "R284"
			(at 0.971804 0.110744 0)
			(unlocked yes)
			(layer "F.SilkS")
			(effects
				(font
					(size 0.635 0.4064)
					(thickness 0.1524)
				)
				(justify left)
			)
		)
		(property "Value" ""
			(at 0 0 0)
			(layer "F.Fab")
			(effects
				(font
					(size 1.27 1.27)
				)
			)
		)
		(duplicate_pad_numbers_are_jumpers no)
		(fp_line
			(start -0.7874 -0.4064)
			(end 0.7874 -0.4064)
			(stroke
				(width 0.1524)
				(type default)
			)
			(layer "F.SilkS")
		)
		(fp_line
			(start -0.7874 0.4064)
			(end -0.7874 -0.4064)
			(stroke
				(width 0.1524)
				(type default)
			)
			(layer "F.SilkS")
		)
		(fp_line
			(start 0.7874 -0.4064)
			(end 0.7874 0.4064)
			(stroke
				(width 0.1524)
				(type default)
			)
			(layer "F.SilkS")
		)
		(fp_line
			(start 0.7874 0.4064)
			(end -0.7874 0.4064)
			(stroke
				(width 0.1524)
				(type default)
			)
			(layer "F.SilkS")
		)
		(fp_poly
			(pts
				(xy -0.508 0.2794) (xy -0.508 0.2286) (xy -0.635 0.2286) (xy -0.635 -0.254) (xy -0.5334 -0.254)
				(xy -0.5334 -0.2794) (xy 0.5334 -0.2794) (xy 0.5334 -0.254) (xy 0.635 -0.254) (xy 0.635 0.254) (xy 0.5334 0.254)
				(xy 0.5334 0.2794)
			)
			(stroke
				(width 0)
				(type default)
			)
			(fill no)
			(layer "F.CrtYd")
		)
		(pad "1" smd rect
			(at 0.40005 0)
			(size 0.4572 0.508)
			(layers "F.Cu" "F.Mask" "F.Paste")
			(net "GND")
		)
		(pad "2" smd rect
			(at -0.40005 0)
			(size 0.4572 0.508)
			(layers "F.Cu" "F.Mask" "F.Paste")
			(net "PCIE_SW_TEST4")
		)
	)
	(footprint ""
		(layer "F.Cu")
		(at 177.653442 -142.838424)
		(property "Reference" "C439"
			(at -5.183632 0.136652 0)
			(unlocked yes)
			(layer "F.SilkS")
			(effects
				(font
					(size 0.7874 0.5842)
					(thickness 0.1524)
				)
				(justify left)
			)
		)
		(property "Value" ""
			(at 0 0 0)
			(layer "F.Fab")
			(effects
				(font
					(size 1.27 1.27)
				)
			)
		)
		(duplicate_pad_numbers_are_jumpers no)
		(fp_line
			(start -1.905 -0.8636)
			(end 1.905 -0.8636)
			(stroke
				(width 0.1524)
				(type default)
			)
			(layer "F.SilkS")
		)
		(fp_line
			(start -1.905 0.8636)
			(end -1.905 -0.8636)
			(stroke
				(width 0.1524)
				(type default)
			)
			(layer "F.SilkS")
		)
		(fp_line
			(start 0 0.8382)
			(end 0 -0.8382)
			(stroke
				(width 0.1524)
				(type default)
			)
			(layer "F.SilkS")
		)
		(fp_line
			(start 1.905 -0.8636)
			(end 1.905 0.8636)
			(stroke
				(width 0.1524)
				(type default)
			)
			(layer "F.SilkS")
		)
		(fp_line
			(start 1.905 0.8636)
			(end -1.905 0.8636)
			(stroke
				(width 0.1524)
				(type default)
			)
			(layer "F.SilkS")
		)
		(fp_rect
			(start -1.524 0.7366)
			(end 1.524 -0.7366)
			(stroke
				(width 0)
				(type default)
			)
			(fill no)
			(layer "F.CrtYd")
		)
		(pad "1" smd rect
			(at 0.94996 0)
			(size 1.1176 1.3716)
			(layers "F.Cu" "F.Mask" "F.Paste")
			(net "P3V3_NODE1")
		)
		(pad "2" smd rect
			(at -0.94996 0)
			(size 1.1176 1.3716)
			(layers "F.Cu" "F.Mask" "F.Paste")
			(net "GND")
		)
	)
	(footprint ""
		(layer "F.Cu")
		(at 106.170476 -165.793928)
		(property "Reference" "R771"
			(at 85.286342 69.748146 0)
			(unlocked yes)
			(layer "F.SilkS")
			(effects
				(font
					(size 0.7874 0.5842)
					(thickness 0.1524)
				)
				(justify left)
			)
		)
		(property "Value" ""
			(at 0 0 0)
			(layer "F.Fab")
			(effects
				(font
					(size 1.27 1.27)
				)
			)
		)
		(duplicate_pad_numbers_are_jumpers no)
		(fp_line
			(start -0.7874 -0.4064)
			(end 0.7874 -0.4064)
			(stroke
				(width 0.1524)
				(type default)
			)
			(layer "F.SilkS")
		)
		(fp_line
			(start -0.7874 0.4064)
			(end -0.7874 -0.4064)
			(stroke
				(width 0.1524)
				(type default)
			)
			(layer "F.SilkS")
		)
		(fp_line
			(start 0.7874 -0.4064)
			(end 0.7874 0.4064)
			(stroke
				(width 0.1524)
				(type default)
			)
			(layer "F.SilkS")
		)
		(fp_line
			(start 0.7874 0.4064)
			(end -0.7874 0.4064)
			(stroke
				(width 0.1524)
				(type default)
			)
			(layer "F.SilkS")
		)
		(fp_poly
			(pts
				(xy -0.508 0.2794) (xy -0.508 0.2286) (xy -0.635 0.2286) (xy -0.635 -0.254) (xy -0.5334 -0.254)
				(xy -0.5334 -0.2794) (xy 0.5334 -0.2794) (xy 0.5334 -0.254) (xy 0.635 -0.254) (xy 0.635 0.254) (xy 0.5334 0.254)
				(xy 0.5334 0.2794)
			)
			(stroke
				(width 0)
				(type default)
			)
			(fill no)
			(layer "F.CrtYd")
		)
		(pad "1" smd rect
			(at 0.40005 0)
			(size 0.4572 0.508)
			(layers "F.Cu" "F.Mask" "F.Paste")
			(net "P3V3_NODE1")
		)
		(pad "2" smd rect
			(at -0.40005 0)
			(size 0.4572 0.508)
			(layers "F.Cu" "F.Mask" "F.Paste")
			(net "FNACTRL2_ADD")
		)
	)
	(footprint ""
		(layer "F.Cu")
		(at 123.70816 -165.507416)
		(property "Reference" "R792"
			(at 30.075378 46.17339 0)
			(unlocked yes)
			(layer "F.SilkS")
			(effects
				(font
					(size 0.7874 0.5842)
					(thickness 0.1524)
				)
				(justify left)
			)
		)
		(property "Value" ""
			(at 0 0 0)
			(layer "F.Fab")
			(effects
				(font
					(size 1.27 1.27)
				)
			)
		)
		(duplicate_pad_numbers_are_jumpers no)
		(fp_line
			(start -0.7874 -0.4064)
			(end 0.7874 -0.4064)
			(stroke
				(width 0.1524)
				(type default)
			)
			(layer "F.SilkS")
		)
		(fp_line
			(start -0.7874 0.4064)
			(end -0.7874 -0.4064)
			(stroke
				(width 0.1524)
				(type default)
			)
			(layer "F.SilkS")
		)
		(fp_line
			(start 0.7874 -0.4064)
			(end 0.7874 0.4064)
			(stroke
				(width 0.1524)
				(type default)
			)
			(layer "F.SilkS")
		)
		(fp_line
			(start 0.7874 0.4064)
			(end -0.7874 0.4064)
			(stroke
				(width 0.1524)
				(type default)
			)
			(layer "F.SilkS")
		)
		(fp_poly
			(pts
				(xy -0.508 0.2794) (xy -0.508 0.2286) (xy -0.635 0.2286) (xy -0.635 -0.254) (xy -0.5334 -0.254)
				(xy -0.5334 -0.2794) (xy 0.5334 -0.2794) (xy 0.5334 -0.254) (xy 0.635 -0.254) (xy 0.635 0.254) (xy 0.5334 0.254)
				(xy 0.5334 0.2794)
			)
			(stroke
				(width 0)
				(type default)
			)
			(fill no)
			(layer "F.CrtYd")
		)
		(pad "1" smd rect
			(at 0.40005 0)
			(size 0.4572 0.508)
			(layers "F.Cu" "F.Mask" "F.Paste")
			(net "GND")
		)
		(pad "2" smd rect
			(at -0.40005 0)
			(size 0.4572 0.508)
			(layers "F.Cu" "F.Mask" "F.Paste")
			(net "COM3_WAKEUP")
		)
	)
	(footprint ""
		(layer "F.Cu")
		(at 61.145166 -96.709992 -90)
		(property "Reference" "R52"
			(at 54.98719 -28.524962 90)
			(unlocked yes)
			(layer "F.SilkS")
			(effects
				(font
					(size 0.7874 0.5842)
					(thickness 0.1524)
				)
				(justify left)
			)
		)
		(property "Value" ""
			(at 0 0 270)
			(layer "F.Fab")
			(effects
				(font
					(size 1.27 1.27)
				)
			)
		)
		(duplicate_pad_numbers_are_jumpers no)
		(fp_line
			(start -0.7874 0.4064)
			(end -0.7874 -0.4064)
			(stroke
				(width 0.1524)
				(type default)
			)
			(layer "F.SilkS")
		)
		(fp_line
			(start 0.7874 0.4064)
			(end -0.7874 0.4064)
			(stroke
				(width 0.1524)
				(type default)
			)
			(layer "F.SilkS")
		)
		(fp_line
			(start -0.7874 -0.4064)
			(end 0.7874 -0.4064)
			(stroke
				(width 0.1524)
				(type default)
			)
			(layer "F.SilkS")
		)
		(fp_line
			(start 0.7874 -0.4064)
			(end 0.7874 0.4064)
			(stroke
				(width 0.1524)
				(type default)
			)
			(layer "F.SilkS")
		)
		(fp_poly
			(pts
				(xy -0.508 0.2794) (xy -0.508 0.2286) (xy -0.635 0.2286) (xy -0.635 -0.254) (xy -0.5334 -0.254)
				(xy -0.5334 -0.2794) (xy 0.5334 -0.2794) (xy 0.5334 -0.254) (xy 0.635 -0.254) (xy 0.635 0.254) (xy 0.5334 0.254)
				(xy 0.5334 0.2794)
			)
			(stroke
				(width 0)
				(type default)
			)
			(fill no)
			(layer "F.CrtYd")
		)
		(pad "1" smd rect
			(at 0.40005 0 270)
			(size 0.4572 0.508)
			(layers "F.Cu" "F.Mask" "F.Paste")
			(net "PD_CPU_NODE1_DFX_GPIO_GRP1_4")
		)
		(pad "2" smd rect
			(at -0.40005 0 270)
			(size 0.4572 0.508)
			(layers "F.Cu" "F.Mask" "F.Paste")
			(net "GND")
		)
	)
	(footprint ""
		(layer "F.Cu")
		(at 193.719958 -146.726656 180)
		(property "Reference" "C474"
			(at -2.372868 0.683514 0)
			(unlocked yes)
			(layer "F.SilkS")
			(effects
				(font
					(size 0.7874 0.5842)
					(thickness 0.1524)
				)
				(justify left)
			)
		)
		(property "Value" ""
			(at 0 0 180)
			(layer "F.Fab")
			(effects
				(font
					(size 1.27 1.27)
				)
			)
		)
		(duplicate_pad_numbers_are_jumpers no)
		(fp_line
			(start 1.905 0.8636)
			(end -1.905 0.8636)
			(stroke
				(width 0.1524)
				(type default)
			)
			(layer "F.SilkS")
		)
		(fp_line
			(start 1.905 -0.8636)
			(end 1.905 0.8636)
			(stroke
				(width 0.1524)
				(type default)
			)
			(layer "F.SilkS")
		)
		(fp_line
			(start 0 0.8382)
			(end 0 -0.8382)
			(stroke
				(width 0.1524)
				(type default)
			)
			(layer "F.SilkS")
		)
		(fp_line
			(start -1.905 0.8636)
			(end -1.905 -0.8636)
			(stroke
				(width 0.1524)
				(type default)
			)
			(layer "F.SilkS")
		)
		(fp_line
			(start -1.905 -0.8636)
			(end 1.905 -0.8636)
			(stroke
				(width 0.1524)
				(type default)
			)
			(layer "F.SilkS")
		)
		(fp_rect
			(start -1.524 0.7366)
			(end 1.524 -0.7366)
			(stroke
				(width 0)
				(type default)
			)
			(fill no)
			(layer "F.CrtYd")
		)
		(pad "1" smd rect
			(at 0.94996 0 180)
			(size 1.1176 1.3716)
			(layers "F.Cu" "F.Mask" "F.Paste")
			(net "P1V9_LAN2")
		)
		(pad "2" smd rect
			(at -0.94996 0 180)
			(size 1.1176 1.3716)
			(layers "F.Cu" "F.Mask" "F.Paste")
			(net "GND")
		)
	)
	(footprint ""
		(layer "F.Cu")
		(at 170.036744 -93.866208 180)
		(property "Reference" "C365"
			(at -4.314952 -0.54991 90)
			(unlocked yes)
			(layer "F.SilkS")
			(effects
				(font
					(size 0.7874 0.5842)
					(thickness 0.1524)
				)
				(justify left)
			)
		)
		(property "Value" ""
			(at 0 0 180)
			(layer "F.Fab")
			(effects
				(font
					(size 1.27 1.27)
				)
			)
		)
		(duplicate_pad_numbers_are_jumpers no)
		(fp_line
			(start 0.7874 0.4064)
			(end -0.7874 0.4064)
			(stroke
				(width 0.1524)
				(type default)
			)
			(layer "F.SilkS")
		)
		(fp_line
			(start 0.7874 -0.4064)
			(end 0.7874 0.4064)
			(stroke
				(width 0.1524)
				(type default)
			)
			(layer "F.SilkS")
		)
		(fp_line
			(start 0 0.381)
			(end 0 -0.381)
			(stroke
				(width 0.1524)
				(type default)
			)
			(layer "F.SilkS")
		)
		(fp_line
			(start -0.7874 0.4064)
			(end -0.7874 -0.4064)
			(stroke
				(width 0.1524)
				(type default)
			)
			(layer "F.SilkS")
		)
		(fp_line
			(start -0.7874 -0.4064)
			(end 0.7874 -0.4064)
			(stroke
				(width 0.1524)
				(type default)
			)
			(layer "F.SilkS")
		)
		(fp_poly
			(pts
				(xy -0.5334 0.254) (xy -0.635 0.254) (xy -0.635 0.2286) (xy -0.635 -0.254) (xy -0.5334 -0.254) (xy -0.5334 -0.2794)
				(xy 0.5334 -0.2794) (xy 0.5334 -0.254) (xy 0.635 -0.254) (xy 0.635 0.254) (xy 0.5334 0.254) (xy 0.5334 0.2794)
				(xy -0.508 0.2794) (xy -0.5334 0.2794)
			)
			(stroke
				(width 0)
				(type default)
			)
			(fill no)
			(layer "F.CrtYd")
		)
		(pad "1" smd rect
			(at 0.40005 0 180)
			(size 0.4572 0.508)
			(layers "F.Cu" "F.Mask" "F.Paste")
			(net "USB_NODE1_XTA1")
		)
		(pad "2" smd rect
			(at -0.40005 0 180)
			(size 0.4572 0.508)
			(layers "F.Cu" "F.Mask" "F.Paste")
			(net "GND")
		)
	)
	(footprint ""
		(layer "F.Cu")
		(at 53.7718 -100.866956 -90)
		(property "Reference" "C138"
			(at -0.702564 -1.347724 90)
			(unlocked yes)
			(layer "F.SilkS")
			(effects
				(font
					(size 0.7874 0.5842)
					(thickness 0.1524)
				)
				(justify left)
			)
		)
		(property "Value" ""
			(at 0 0 270)
			(layer "F.Fab")
			(effects
				(font
					(size 1.27 1.27)
				)
			)
		)
		(duplicate_pad_numbers_are_jumpers no)
		(fp_line
			(start -0.7874 0.4064)
			(end -0.7874 -0.4064)
			(stroke
				(width 0.1524)
				(type default)
			)
			(layer "F.SilkS")
		)
		(fp_line
			(start 0.7874 0.4064)
			(end -0.7874 0.4064)
			(stroke
				(width 0.1524)
				(type default)
			)
			(layer "F.SilkS")
		)
		(fp_line
			(start 0 0.381)
			(end 0 -0.381)
			(stroke
				(width 0.1524)
				(type default)
			)
			(layer "F.SilkS")
		)
		(fp_line
			(start -0.7874 -0.4064)
			(end 0.7874 -0.4064)
			(stroke
				(width 0.1524)
				(type default)
			)
			(layer "F.SilkS")
		)
		(fp_line
			(start 0.7874 -0.4064)
			(end 0.7874 0.4064)
			(stroke
				(width 0.1524)
				(type default)
			)
			(layer "F.SilkS")
		)
		(fp_poly
			(pts
				(xy -0.5334 0.254) (xy -0.635 0.254) (xy -0.635 0.2286) (xy -0.635 -0.254) (xy -0.5334 -0.254) (xy -0.5334 -0.2794)
				(xy 0.5334 -0.2794) (xy 0.5334 -0.254) (xy 0.635 -0.254) (xy 0.635 0.254) (xy 0.5334 0.254) (xy 0.5334 0.2794)
				(xy -0.508 0.2794) (xy -0.5334 0.2794)
			)
			(stroke
				(width 0)
				(type default)
			)
			(fill no)
			(layer "F.CrtYd")
		)
		(pad "1" smd rect
			(at 0.40005 0 270)
			(size 0.4572 0.508)
			(layers "F.Cu" "F.Mask" "F.Paste")
			(net "A_CPU1_NODE1_THERMDA")
		)
		(pad "2" smd rect
			(at -0.40005 0 270)
			(size 0.4572 0.508)
			(layers "F.Cu" "F.Mask" "F.Paste")
			(net "A_CPU1_NODE1_THERMDC")
		)
	)
	(footprint ""
		(layer "F.Cu")
		(at 98.389948 -138.41349 -90)
		(property "Reference" "C812"
			(at 0.82296 -1.559052 90)
			(unlocked yes)
			(layer "F.SilkS")
			(effects
				(font
					(size 0.7874 0.5842)
					(thickness 0.1524)
				)
				(justify left)
			)
		)
		(property "Value" ""
			(at 0 0 270)
			(layer "F.Fab")
			(effects
				(font
					(size 1.27 1.27)
				)
			)
		)
		(duplicate_pad_numbers_are_jumpers no)
		(fp_line
			(start -1.905 0.8636)
			(end -1.905 -0.8636)
			(stroke
				(width 0.1524)
				(type default)
			)
			(layer "F.SilkS")
		)
		(fp_line
			(start 1.905 0.8636)
			(end -1.905 0.8636)
			(stroke
				(width 0.1524)
				(type default)
			)
			(layer "F.SilkS")
		)
		(fp_line
			(start 0 0.8382)
			(end 0 -0.8382)
			(stroke
				(width 0.1524)
				(type default)
			)
			(layer "F.SilkS")
		)
		(fp_line
			(start -1.905 -0.8636)
			(end 1.905 -0.8636)
			(stroke
				(width 0.1524)
				(type default)
			)
			(layer "F.SilkS")
		)
		(fp_line
			(start 1.905 -0.8636)
			(end 1.905 0.8636)
			(stroke
				(width 0.1524)
				(type default)
			)
			(layer "F.SilkS")
		)
		(fp_rect
			(start -1.524 0.7366)
			(end 1.524 -0.7366)
			(stroke
				(width 0)
				(type default)
			)
			(fill no)
			(layer "F.CrtYd")
		)
		(pad "1" smd rect
			(at 0.94996 0 270)
			(size 1.1176 1.3716)
			(layers "F.Cu" "F.Mask" "F.Paste")
			(net "P1V05_SUS_NODE1")
		)
		(pad "2" smd rect
			(at -0.94996 0 270)
			(size 1.1176 1.3716)
			(layers "F.Cu" "F.Mask" "F.Paste")
			(net "GND")
		)
	)
	(footprint ""
		(layer "F.Cu")
		(at 114.537998 -123.911106 90)
		(property "Reference" "PC89"
			(at -1.144016 5.335524 90)
			(unlocked yes)
			(layer "F.SilkS")
			(effects
				(font
					(size 0.7874 0.5842)
					(thickness 0.1524)
				)
				(justify left)
			)
		)
		(property "Value" ""
			(at 0 0 90)
			(layer "F.Fab")
			(effects
				(font
					(size 1.27 1.27)
				)
			)
		)
		(duplicate_pad_numbers_are_jumpers no)
		(fp_line
			(start 0.7874 -0.4064)
			(end 0.7874 0.4064)
			(stroke
				(width 0.1524)
				(type default)
			)
			(layer "F.SilkS")
		)
		(fp_line
			(start -0.7874 -0.4064)
			(end 0.7874 -0.4064)
			(stroke
				(width 0.1524)
				(type default)
			)
			(layer "F.SilkS")
		)
		(fp_line
			(start 0 0.381)
			(end 0 -0.381)
			(stroke
				(width 0.1524)
				(type default)
			)
			(layer "F.SilkS")
		)
		(fp_line
			(start 0.7874 0.4064)
			(end -0.7874 0.4064)
			(stroke
				(width 0.1524)
				(type default)
			)
			(layer "F.SilkS")
		)
		(fp_line
			(start -0.7874 0.4064)
			(end -0.7874 -0.4064)
			(stroke
				(width 0.1524)
				(type default)
			)
			(layer "F.SilkS")
		)
		(fp_poly
			(pts
				(xy -0.5334 0.254) (xy -0.635 0.254) (xy -0.635 0.2286) (xy -0.635 -0.254) (xy -0.5334 -0.254) (xy -0.5334 -0.2794)
				(xy 0.5334 -0.2794) (xy 0.5334 -0.254) (xy 0.635 -0.254) (xy 0.635 0.254) (xy 0.5334 0.254) (xy 0.5334 0.2794)
				(xy -0.508 0.2794) (xy -0.5334 0.2794)
			)
			(stroke
				(width 0)
				(type default)
			)
			(fill no)
			(layer "F.CrtYd")
		)
		(pad "1" smd rect
			(at 0.40005 0 90)
			(size 0.4572 0.508)
			(layers "F.Cu" "F.Mask" "F.Paste")
			(net "SW_VR_PVCCP_NODE1_VIN_FLT")
		)
		(pad "2" smd rect
			(at -0.40005 0 90)
			(size 0.4572 0.508)
			(layers "F.Cu" "F.Mask" "F.Paste")
			(net "GND")
		)
	)
	(footprint ""
		(layer "F.Cu")
		(at 65.253108 -112.672368 180)
		(property "Reference" "R1111"
			(at 4.968748 0.0254 0)
			(unlocked yes)
			(layer "F.SilkS")
			(effects
				(font
					(size 0.7874 0.5842)
					(thickness 0.1524)
				)
				(justify left)
			)
		)
		(property "Value" ""
			(at 0 0 180)
			(layer "F.Fab")
			(effects
				(font
					(size 1.27 1.27)
				)
			)
		)
		(duplicate_pad_numbers_are_jumpers no)
		(fp_line
			(start 0.7874 0.4064)
			(end -0.7874 0.4064)
			(stroke
				(width 0.1524)
				(type default)
			)
			(layer "F.SilkS")
		)
		(fp_line
			(start 0.7874 -0.4064)
			(end 0.7874 0.4064)
			(stroke
				(width 0.1524)
				(type default)
			)
			(layer "F.SilkS")
		)
		(fp_line
			(start -0.7874 0.4064)
			(end -0.7874 -0.4064)
			(stroke
				(width 0.1524)
				(type default)
			)
			(layer "F.SilkS")
		)
		(fp_line
			(start -0.7874 -0.4064)
			(end 0.7874 -0.4064)
			(stroke
				(width 0.1524)
				(type default)
			)
			(layer "F.SilkS")
		)
		(fp_poly
			(pts
				(xy -0.508 0.2794) (xy -0.508 0.2286) (xy -0.635 0.2286) (xy -0.635 -0.254) (xy -0.5334 -0.254)
				(xy -0.5334 -0.2794) (xy 0.5334 -0.2794) (xy 0.5334 -0.254) (xy 0.635 -0.254) (xy 0.635 0.254) (xy 0.5334 0.254)
				(xy 0.5334 0.2794)
			)
			(stroke
				(width 0)
				(type default)
			)
			(fill no)
			(layer "F.CrtYd")
		)
		(pad "1" smd rect
			(at 0.40005 0 180)
			(size 0.4572 0.508)
			(layers "F.Cu" "F.Mask" "F.Paste")
			(net "P5V_STB_NODE1")
		)
		(pad "2" smd rect
			(at -0.40005 0 180)
			(size 0.4572 0.508)
			(layers "F.Cu" "F.Mask" "F.Paste")
			(net "FM_CPLD_NODE1_P1V8_EN_LV")
		)
	)
)
